# TIMECARD (Time Appliance Project (Time Card)) — schematic netlist excerpt (pin names and nets, part order shuffled) for the footprints in the layout excerpt that follows; sources: Cadence DE-HDL packaged netlist, KiCad conversion of R4006-B0001-02_R01.brd

C200  CAPACITOR  0.1UF 10V 10%  pkg SMC_0402R_H022  page 14 : \1\ = XP1R8V_FPGA_VCCAUX ; \2\ = SG
C96  CAPACITOR  0.1UF 25V 10%  pkg SMC_0402R_H022  page 24 : \1\ = FT4232_VREGOUT ; \2\ = SG

(kicad_pcb
	(version 20260206)
	(generator "pcbnew")
	(generator_version "10.0")
	(general
		(thickness 1.6)
		(legacy_teardrops no)
	)
	(paper "A4")
	(title_block
		(title "timecard-production-celestica-r4006 — R4006-B0001-02_R01.brd")
		(comment 1 "Time Appliance Project (Time Card) / footprints 873-874 of 1113")
	)
	(layers
		(0 "F.Cu" signal "TOP")
		(4 "In1.Cu" signal "L02_GND1")
		(6 "In2.Cu" signal "L03_SIG1")
		(8 "In3.Cu" signal "L04_GND2")
		(10 "In4.Cu" signal "L05_VCC1")
		(12 "In5.Cu" signal "L06_VCC2")
		(14 "In6.Cu" signal "L07_GND3")
		(16 "In7.Cu" signal "L08_SIG2")
		(18 "In8.Cu" signal "L09_GND4")
		(2 "B.Cu" signal "BOTTOM")
		(9 "F.Adhes" user "F.Adhesive")
		(11 "B.Adhes" user "B.Adhesive")
		(13 "F.Paste" user "Package Geometry/Pastemask Top")
		(15 "B.Paste" user "Package Geometry/Pastemask Bottom")
		(5 "F.SilkS" user "Ref Des/Silkscreen Top")
		(7 "B.SilkS" user "Ref Des/Silkscreen Bottom")
		(1 "F.Mask" user "Board Geometry/Soldermask Top")
		(3 "B.Mask" user "Board Geometry/Soldermask Bottom")
		(17 "Dwgs.User" user "User.Drawings")
		(19 "Cmts.User" user "User.Comments")
		(21 "Eco1.User" user "User.Eco1")
		(23 "Eco2.User" user "User.Eco2")
		(25 "Edge.Cuts" user "Board Geometry/Outline")
		(27 "Margin" user)
		(31 "F.CrtYd" user "Package Geometry/Place Bound Top")
		(29 "B.CrtYd" user "Package Geometry/Place Bound Bottom")
		(35 "F.Fab" user "Ref Des/Assembly Top")
		(33 "B.Fab" user "Ref Des/Assembly Bottom")
	)
	(footprint ""
		(layer "B.Cu")
		(at 107.347004 -45.823124)
		(property "Reference" "C200"
			(at -2.318004 0.261874 0)
			(unlocked yes)
			(layer "B.SilkS")
			(effects
				(font
					(size 0.635 0.4064)
					(thickness 0.1524)
				)
				(justify mirror)
			)
		)
		(property "Value" "VAL*"
			(at 0 3.718306 0)
			(unlocked yes)
			(layer "B.Fab")
			(hide yes)
			(effects
				(font
					(size 0.7874 0.5842)
					(thickness 0.127)
				)
				(justify mirror)
			)
		)
		(property "Tolerance" "TOL*"
			(at 0 4.861306 0)
			(unlocked yes)
			(layer "Cmts.User")
			(hide yes)
			(effects
				(font
					(size 0.7874 0.5842)
					(thickness 0.127)
				)
				(justify mirror)
			)
		)
		(property "User Part Number" "PARTNUM*"
			(at 0 2.575306 0)
			(unlocked yes)
			(layer "Cmts.User")
			(hide yes)
			(effects
				(font
					(size 0.7874 0.5842)
					(thickness 0.127)
				)
				(justify mirror)
			)
		)
		(property "Device Type" "CAPACITOR-G105-0B104-CK,0.1UF,A"
			(at 0 1.432306 0)
			(unlocked yes)
			(layer "B.Fab")
			(hide yes)
			(effects
				(font
					(size 0.7874 0.5842)
					(thickness 0.127)
				)
				(justify mirror)
			)
		)
		(duplicate_pad_numbers_are_jumpers no)
		(fp_line
			(start -0.970026 -0.4699)
			(end -0.970026 0.4699)
			(stroke
				(width 0.1)
				(type default)
			)
			(layer "B.SilkS")
		)
		(fp_line
			(start -0.970026 0.4699)
			(end 0.970026 0.4699)
			(stroke
				(width 0.1)
				(type default)
			)
			(layer "B.SilkS")
		)
		(fp_line
			(start 0.970026 -0.4699)
			(end -0.970026 -0.4699)
			(stroke
				(width 0.1)
				(type default)
			)
			(layer "B.SilkS")
		)
		(fp_line
			(start 0.970026 0.4699)
			(end 0.970026 -0.4699)
			(stroke
				(width 0.1)
				(type default)
			)
			(layer "B.SilkS")
		)
		(fp_poly
			(pts
				(xy 0.970026 0.4699) (xy -0.970026 0.4699) (xy -0.970026 -0.4699) (xy 0.970026 -0.4699)
			)
			(stroke
				(width 0)
				(type default)
			)
			(fill no)
			(layer "B.CrtYd")
		)
		(fp_line
			(start -0.508 -0.3048)
			(end -0.508 0.3048)
			(stroke
				(width 0.1)
				(type default)
			)
			(layer "B.Fab")
		)
		(fp_line
			(start -0.508 0.3048)
			(end 0.508 0.3048)
			(stroke
				(width 0.1)
				(type default)
			)
			(layer "B.Fab")
		)
		(fp_line
			(start 0.508 -0.3048)
			(end -0.508 -0.3048)
			(stroke
				(width 0.1)
				(type default)
			)
			(layer "B.Fab")
		)
		(fp_line
			(start 0.508 0.3048)
			(end 0.508 -0.3048)
			(stroke
				(width 0.1)
				(type default)
			)
			(layer "B.Fab")
		)
		(pad "1" smd circle
			(at 0.500126 0 180)
			(size 0.635 0.635)
			(layers "B.Cu" "B.Mask" "B.Paste")
			(net "XP1R8V_FPGA_VCCAUX")
		)
		(pad "2" smd circle
			(at -0.500126 0 180)
			(size 0.635 0.635)
			(layers "B.Cu" "B.Mask" "B.Paste")
			(net "SG")
		)
	)
	(footprint ""
		(layer "B.Cu")
		(at 34.417 -88.9 180)
		(property "Reference" "C96"
			(at -0.127 -1.18237 0)
			(unlocked yes)
			(layer "B.SilkS")
			(effects
				(font
					(size 0.7874 0.5842)
					(thickness 0.1524)
				)
				(justify mirror)
			)
		)
		(property "Value" "VAL*"
			(at -0.0762 2.067306 180)
			(unlocked yes)
			(layer "B.Fab")
			(hide yes)
			(effects
				(font
					(size 0.7874 0.5842)
					(thickness 0.1524)
				)
				(justify mirror)
			)
		)
		(property "Tolerance" "TOL*"
			(at -0.0762 3.032506 180)
			(unlocked yes)
			(layer "Cmts.User")
			(hide yes)
			(effects
				(font
					(size 0.7874 0.5842)
					(thickness 0.1524)
				)
				(justify mirror)
			)
		)
		(property "User Part Number" "PARTNUM*"
			(at -0.1016 4.023106 180)
			(unlocked yes)
			(layer "Cmts.User")
			(hide yes)
			(effects
				(font
					(size 0.7874 0.5842)
					(thickness 0.1524)
				)
				(justify mirror)
			)
		)
		(property "Device Type" "CAPACITOR-G105-0B104-EK,0.1UF,A"
			(at -0.0508 1.127506 180)
			(unlocked yes)
			(layer "B.Fab")
			(hide yes)
			(effects
				(font
					(size 0.7874 0.5842)
					(thickness 0.1524)
				)
				(justify mirror)
			)
		)
		(duplicate_pad_numbers_are_jumpers no)
		(fp_line
			(start 1.143 0.5588)
			(end -1.143 0.5588)
			(stroke
				(width 0.1)
				(type default)
			)
			(layer "B.SilkS")
		)
		(fp_line
			(start 1.143 -0.5588)
			(end 1.143 0.5588)
			(stroke
				(width 0.1)
				(type default)
			)
			(layer "B.SilkS")
		)
		(fp_line
			(start -1.143 0.5588)
			(end -1.143 -0.5588)
			(stroke
				(width 0.1)
				(type default)
			)
			(layer "B.SilkS")
		)
		(fp_line
			(start -1.143 -0.5588)
			(end 1.143 -0.5588)
			(stroke
				(width 0.1)
				(type default)
			)
			(layer "B.SilkS")
		)
		(fp_rect
			(start 1.143 0.5588)
			(end -1.143 -0.5588)
			(stroke
				(width 0)
				(type default)
			)
			(fill no)
			(layer "B.CrtYd")
		)
		(fp_line
			(start 0.508 0.3048)
			(end -0.508 0.3048)
			(stroke
				(width 0.1)
				(type default)
			)
			(layer "B.Fab")
		)
		(fp_line
			(start 0.508 -0.3048)
			(end 0.508 0.3048)
			(stroke
				(width 0.1)
				(type default)
			)
			(layer "B.Fab")
		)
		(fp_line
			(start -0.508 0.3048)
			(end -0.508 -0.3048)
			(stroke
				(width 0.1)
				(type default)
			)
			(layer "B.Fab")
		)
		(fp_line
			(start -0.508 -0.3048)
			(end 0.508 -0.3048)
			(stroke
				(width 0.1)
				(type default)
			)
			(layer "B.Fab")
		)
		(pad "1" smd rect
			(at 0.5334 0)
			(size 0.7112 0.6096)
			(layers "B.Cu" "B.Mask" "B.Paste")
			(net "FT4232_VREGOUT")
		)
		(pad "2" smd rect
			(at -0.5334 0)
			(size 0.7112 0.6096)
			(layers "B.Cu" "B.Mask" "B.Paste")
			(net "SG")
		)
		(zone
			(layer "B.Cu")
			(hatch none 0.5)
			(connect_pads
				(clearance 0)
			)
			(min_thickness 0.25)
			(keepout
				(tracks allowed)
				(vias not_allowed)
				(pads allowed)
				(copperpour not_allowed)
				(footprints allowed)
			)
			(placement
				(enabled no)
				(sheetname "")
			)
			(fill
				(thermal_gap 0.5)
				(thermal_bridge_width 0.5)
				(island_removal_mode 0)
			)
			(polygon
				(pts
					(xy 34.3408 -89.2048) (xy 34.3408 -88.5952) (xy 34.4932 -88.5952) (xy 34.4932 -89.2048)
				)
			)
		)
	)
)
